(kicad_pcb
	(version 20260206)
	(generator "pcbnew")
	(generator_version "10.0")
	(general
		(thickness 1.6)
		(legacy_teardrops no)
	)
	(paper "A4")
	(title_block
		(title "pdpb — Lightning_PDPB_BRD.brd")
		(comment 1 "Lightning (Wiwynn / Facebook NVMe JBOF) / footprints 945-951 of 1140")
	)
	(layers
		(0 "F.Cu" signal "TOP")
		(4 "In1.Cu" signal "L2GND")
		(6 "In2.Cu" signal "L3")
		(8 "In3.Cu" signal "L4VCC")
		(10 "In4.Cu" signal "L5VCC")
		(12 "In5.Cu" signal "L6")
		(14 "In6.Cu" signal "L7GND")
		(2 "B.Cu" signal "BOTTOM")
		(9 "F.Adhes" user "F.Adhesive")
		(11 "B.Adhes" user "B.Adhesive")
		(13 "F.Paste" user "Package Geometry/Pastemask Top")
		(15 "B.Paste" user "Package Geometry/Pastemask Bottom")
		(5 "F.SilkS" user "Ref Des/Silkscreen Top")
		(7 "B.SilkS" user "Ref Des/Silkscreen Bottom")
		(1 "F.Mask" user "Board Geometry/Soldermask Top")
		(3 "B.Mask" user "Board Geometry/Soldermask Bottom")
		(17 "Dwgs.User" user "User.Drawings")
		(19 "Cmts.User" user "User.Comments")
		(21 "Eco1.User" user "User.Eco1")
		(23 "Eco2.User" user "User.Eco2")
		(25 "Edge.Cuts" user "Board Geometry/Outline")
		(27 "Margin" user)
		(31 "F.CrtYd" user "Package Geometry/Place Bound Top")
		(29 "B.CrtYd" user "Package Geometry/Place Bound Bottom")
		(35 "F.Fab" user "Ref Des/Assembly Top")
		(33 "B.Fab" user "Ref Des/Assembly Bottom")
	)
	(footprint ""
		(layer "F.Cu")
		(at 96.774 -222.885 -90)
		(property "Reference" "C9369"
			(at 0 0 270)
			(layer "F.SilkS")
			(hide yes)
			(effects
				(font
					(size 1.27 1.27)
				)
			)
		)
		(property "Value" "SC1KP50V2KX-1GP"
			(at 1.1811 -2.7051 270)
			(unlocked yes)
			(layer "F.Fab")
			(hide yes)
			(effects
				(font
					(size 1.016 1.016)
					(thickness 0.1524)
				)
			)
		)
		(property "Device Type" "C402H22"
			(at 1.1811 -4.2291 270)
			(unlocked yes)
			(layer "F.Fab")
			(hide yes)
			(effects
				(font
					(size 1.016 1.016)
					(thickness 0.1524)
				)
			)
		)
		(duplicate_pad_numbers_are_jumpers no)
		(fp_rect
			(start -0.4318 0.9525)
			(end 0.4318 -0.9525)
			(stroke
				(width 0)
				(type default)
			)
			(fill no)
			(layer "F.CrtYd")
		)
		(fp_rect
			(start -0.4318 0.9525)
			(end 0.4318 -0.9525)
			(stroke
				(width 0)
				(type default)
			)
			(fill no)
			(layer "F.Fab")
		)
		(pad "1" smd custom
			(at 0 -0.4445 270)
			(size 0.1524 0.1524)
			(layers "F.Cu" "F.Mask" "F.Paste")
			(net "SSD7_CLK0_OE_R_N")
			(options
				(clearance outline)
				(anchor circle)
			)
			(primitives
				(gr_poly
					(pts
						(arc
							(start 0.3048 -0.2032)
							(mid 0.275042 -0.275042)
							(end 0.2032 -0.3048)
						)
						(arc
							(start -0.2032 -0.3048)
							(mid -0.275042 -0.275042)
							(end -0.3048 -0.2032)
						)
						(arc
							(start -0.3048 0.2032)
							(mid -0.275042 0.275042)
							(end -0.2032 0.3048)
						)
						(arc
							(start 0.2032 0.3048)
							(mid 0.275042 0.275042)
							(end 0.3048 0.2032)
						)
					)
					(width 0)
					(fill yes)
				)
			)
		)
		(pad "2" smd custom
			(at 0 0.4445 270)
			(size 0.1524 0.1524)
			(layers "F.Cu" "F.Mask" "F.Paste")
			(net "GND")
			(options
				(clearance outline)
				(anchor circle)
			)
			(primitives
				(gr_poly
					(pts
						(arc
							(start 0.3048 -0.2032)
							(mid 0.275042 -0.275042)
							(end 0.2032 -0.3048)
						)
						(arc
							(start -0.2032 -0.3048)
							(mid -0.275042 -0.275042)
							(end -0.3048 -0.2032)
						)
						(arc
							(start -0.3048 0.2032)
							(mid -0.275042 0.275042)
							(end -0.2032 0.3048)
						)
						(arc
							(start 0.2032 0.3048)
							(mid 0.275042 0.275042)
							(end 0.3048 0.2032)
						)
					)
					(width 0)
					(fill yes)
				)
			)
		)
	)
	(footprint ""
		(layer "F.Cu")
		(at 72.009 -454.66)
		(property "Reference" "R346"
			(at 0 0 0)
			(layer "F.SilkS")
			(hide yes)
			(effects
				(font
					(size 1.27 1.27)
				)
			)
		)
		(property "Value" "4K7R2F-GP"
			(at 0.064008 -3.993896 0)
			(unlocked yes)
			(layer "F.Fab")
			(hide yes)
			(effects
				(font
					(size 1.016 1.016)
					(thickness 0.1524)
				)
			)
		)
		(property "Device Type" "R402H16"
			(at 0.064008 -5.517896 0)
			(unlocked yes)
			(layer "F.Fab")
			(hide yes)
			(effects
				(font
					(size 1.016 1.016)
					(thickness 0.1524)
				)
			)
		)
		(duplicate_pad_numbers_are_jumpers no)
		(fp_line
			(start -0.508 -0.9398)
			(end -0.508 0.9398)
			(stroke
				(width 0.1524)
				(type default)
			)
			(layer "F.SilkS")
		)
		(fp_line
			(start 0.508 -0.9398)
			(end -0.508 -0.9398)
			(stroke
				(width 0.1524)
				(type default)
			)
			(layer "F.SilkS")
		)
		(fp_rect
			(start -0.508 0.9398)
			(end 0.508 -0.9398)
			(stroke
				(width 0)
				(type default)
			)
			(fill no)
			(layer "F.CrtYd")
		)
		(fp_rect
			(start -0.508 0.9398)
			(end 0.508 -0.9398)
			(stroke
				(width 0)
				(type default)
			)
			(fill no)
			(layer "F.Fab")
		)
		(pad "1" smd custom
			(at 0 -0.4445)
			(size 0.1397 0.1397)
			(layers "F.Cu" "F.Mask" "F.Paste")
			(net "P3V3")
			(options
				(clearance outline)
				(anchor circle)
			)
			(primitives
				(gr_poly
					(pts
						(arc
							(start -0.1778 -0.2794)
							(mid -0.249642 -0.249642)
							(end -0.2794 -0.1778)
						)
						(arc
							(start -0.2794 0.1778)
							(mid -0.249642 0.249642)
							(end -0.1778 0.2794)
						)
						(arc
							(start 0.1778 0.2794)
							(mid 0.249642 0.249642)
							(end 0.2794 0.1778)
						)
						(arc
							(start 0.2794 -0.1778)
							(mid 0.249642 -0.249642)
							(end 0.1778 -0.2794)
						)
					)
					(width 0)
					(fill yes)
				)
			)
		)
		(pad "2" smd custom
			(at 0 0.4445)
			(size 0.1397 0.1397)
			(layers "F.Cu" "F.Mask" "F.Paste")
			(net "EEPROM_A1")
			(options
				(clearance outline)
				(anchor circle)
			)
			(primitives
				(gr_poly
					(pts
						(arc
							(start -0.1778 -0.2794)
							(mid -0.249642 -0.249642)
							(end -0.2794 -0.1778)
						)
						(arc
							(start -0.2794 0.1778)
							(mid -0.249642 0.249642)
							(end -0.1778 0.2794)
						)
						(arc
							(start 0.1778 0.2794)
							(mid 0.249642 0.249642)
							(end 0.2794 0.1778)
						)
						(arc
							(start 0.2794 -0.1778)
							(mid 0.249642 -0.249642)
							(end 0.1778 -0.2794)
						)
					)
					(width 0)
					(fill yes)
				)
			)
		)
	)
	(footprint ""
		(layer "F.Cu")
		(at 29.03093 -84.662518)
		(property "Reference" "SR1109"
			(at 0 0 0)
			(layer "F.SilkS")
			(hide yes)
			(effects
				(font
					(size 1.27 1.27)
				)
			)
		)
		(property "Value" "4K7R2F-GP"
			(at 0.064008 -3.993896 0)
			(unlocked yes)
			(layer "F.Fab")
			(hide yes)
			(effects
				(font
					(size 1.016 1.016)
					(thickness 0.1524)
				)
			)
		)
		(property "Device Type" "R402H16"
			(at 0.064008 -5.517896 0)
			(unlocked yes)
			(layer "F.Fab")
			(hide yes)
			(effects
				(font
					(size 1.016 1.016)
					(thickness 0.1524)
				)
			)
		)
		(duplicate_pad_numbers_are_jumpers no)
		(fp_line
			(start -0.508 -0.9398)
			(end -0.508 0.9398)
			(stroke
				(width 0.1524)
				(type default)
			)
			(layer "F.SilkS")
		)
		(fp_line
			(start 0.508 -0.9398)
			(end -0.508 -0.9398)
			(stroke
				(width 0.1524)
				(type default)
			)
			(layer "F.SilkS")
		)
		(fp_rect
			(start -0.508 0.9398)
			(end 0.508 -0.9398)
			(stroke
				(width 0)
				(type default)
			)
			(fill no)
			(layer "F.CrtYd")
		)
		(fp_rect
			(start -0.508 0.9398)
			(end 0.508 -0.9398)
			(stroke
				(width 0)
				(type default)
			)
			(fill no)
			(layer "F.Fab")
		)
		(pad "1" smd custom
			(at 0 -0.4445)
			(size 0.1397 0.1397)
			(layers "F.Cu" "F.Mask" "F.Paste")
			(net "P3V3")
			(options
				(clearance outline)
				(anchor circle)
			)
			(primitives
				(gr_poly
					(pts
						(arc
							(start -0.1778 -0.2794)
							(mid -0.249642 -0.249642)
							(end -0.2794 -0.1778)
						)
						(arc
							(start -0.2794 0.1778)
							(mid -0.249642 0.249642)
							(end -0.1778 0.2794)
						)
						(arc
							(start 0.1778 0.2794)
							(mid 0.249642 0.249642)
							(end 0.2794 0.1778)
						)
						(arc
							(start 0.2794 -0.1778)
							(mid 0.249642 -0.249642)
							(end 0.1778 -0.2794)
						)
					)
					(width 0)
					(fill yes)
				)
			)
		)
		(pad "2" smd custom
			(at 0 0.4445)
			(size 0.1397 0.1397)
			(layers "F.Cu" "F.Mask" "F.Paste")
			(net "DUALPORTEN#9")
			(options
				(clearance outline)
				(anchor circle)
			)
			(primitives
				(gr_poly
					(pts
						(arc
							(start -0.1778 -0.2794)
							(mid -0.249642 -0.249642)
							(end -0.2794 -0.1778)
						)
						(arc
							(start -0.2794 0.1778)
							(mid -0.249642 0.249642)
							(end -0.1778 0.2794)
						)
						(arc
							(start 0.1778 0.2794)
							(mid 0.249642 0.249642)
							(end 0.2794 0.1778)
						)
						(arc
							(start 0.2794 -0.1778)
							(mid 0.249642 -0.249642)
							(end 0.1778 -0.2794)
						)
					)
					(width 0)
					(fill yes)
				)
			)
		)
	)
	(footprint ""
		(layer "F.Cu")
		(at 31.9278 -12.5984)
		(property "Reference" "SR1119"
			(at 0 0 0)
			(layer "F.SilkS")
			(hide yes)
			(effects
				(font
					(size 1.27 1.27)
				)
			)
		)
		(property "Value" "4K7R2F-GP"
			(at 0.064008 -3.993896 0)
			(unlocked yes)
			(layer "F.Fab")
			(hide yes)
			(effects
				(font
					(size 1.016 1.016)
					(thickness 0.1524)
				)
			)
		)
		(property "Device Type" "R402H16"
			(at 0.064008 -5.517896 0)
			(unlocked yes)
			(layer "F.Fab")
			(hide yes)
			(effects
				(font
					(size 1.016 1.016)
					(thickness 0.1524)
				)
			)
		)
		(duplicate_pad_numbers_are_jumpers no)
		(fp_line
			(start -0.508 -0.9398)
			(end -0.508 0.9398)
			(stroke
				(width 0.1524)
				(type default)
			)
			(layer "F.SilkS")
		)
		(fp_line
			(start 0.508 -0.9398)
			(end -0.508 -0.9398)
			(stroke
				(width 0.1524)
				(type default)
			)
			(layer "F.SilkS")
		)
		(fp_rect
			(start -0.508 0.9398)
			(end 0.508 -0.9398)
			(stroke
				(width 0)
				(type default)
			)
			(fill no)
			(layer "F.CrtYd")
		)
		(fp_rect
			(start -0.508 0.9398)
			(end 0.508 -0.9398)
			(stroke
				(width 0)
				(type default)
			)
			(fill no)
			(layer "F.Fab")
		)
		(pad "1" smd custom
			(at 0 -0.4445)
			(size 0.1397 0.1397)
			(layers "F.Cu" "F.Mask" "F.Paste")
			(net "P3V3")
			(options
				(clearance outline)
				(anchor circle)
			)
			(primitives
				(gr_poly
					(pts
						(arc
							(start -0.1778 -0.2794)
							(mid -0.249642 -0.249642)
							(end -0.2794 -0.1778)
						)
						(arc
							(start -0.2794 0.1778)
							(mid -0.249642 0.249642)
							(end -0.1778 0.2794)
						)
						(arc
							(start 0.1778 0.2794)
							(mid 0.249642 0.249642)
							(end 0.2794 0.1778)
						)
						(arc
							(start 0.2794 -0.1778)
							(mid 0.249642 -0.249642)
							(end 0.1778 -0.2794)
						)
					)
					(width 0)
					(fill yes)
				)
			)
		)
		(pad "2" smd custom
			(at 0 0.4445)
			(size 0.1397 0.1397)
			(layers "F.Cu" "F.Mask" "F.Paste")
			(net "DUALPORTEN#14")
			(options
				(clearance outline)
				(anchor circle)
			)
			(primitives
				(gr_poly
					(pts
						(arc
							(start -0.1778 -0.2794)
							(mid -0.249642 -0.249642)
							(end -0.2794 -0.1778)
						)
						(arc
							(start -0.2794 0.1778)
							(mid -0.249642 0.249642)
							(end -0.1778 0.2794)
						)
						(arc
							(start 0.1778 0.2794)
							(mid 0.249642 0.249642)
							(end 0.2794 0.1778)
						)
						(arc
							(start 0.2794 -0.1778)
							(mid 0.249642 -0.249642)
							(end 0.1778 -0.2794)
						)
					)
					(width 0)
					(fill yes)
				)
			)
		)
	)
	(footprint ""
		(layer "F.Cu")
		(at 28.8671 -197.5231 180)
		(property "Reference" "R9834"
			(at 0 0 180)
			(layer "F.SilkS")
			(hide yes)
			(effects
				(font
					(size 1.27 1.27)
				)
			)
		)
		(property "Value" "47KR2J-2-GP"
			(at 0.064008 -3.993896 180)
			(unlocked yes)
			(layer "F.Fab")
			(hide yes)
			(effects
				(font
					(size 1.016 1.016)
					(thickness 0.1524)
				)
			)
		)
		(property "Device Type" "R402H16"
			(at 0.064008 -5.517896 180)
			(unlocked yes)
			(layer "F.Fab")
			(hide yes)
			(effects
				(font
					(size 1.016 1.016)
					(thickness 0.1524)
				)
			)
		)
		(duplicate_pad_numbers_are_jumpers no)
		(fp_line
			(start 0.508 -0.9398)
			(end -0.508 -0.9398)
			(stroke
				(width 0.1524)
				(type default)
			)
			(layer "F.SilkS")
		)
		(fp_line
			(start -0.508 -0.9398)
			(end -0.508 0.9398)
			(stroke
				(width 0.1524)
				(type default)
			)
			(layer "F.SilkS")
		)
		(fp_rect
			(start -0.508 0.9398)
			(end 0.508 -0.9398)
			(stroke
				(width 0)
				(type default)
			)
			(fill no)
			(layer "F.CrtYd")
		)
		(fp_rect
			(start -0.508 0.9398)
			(end 0.508 -0.9398)
			(stroke
				(width 0)
				(type default)
			)
			(fill no)
			(layer "F.Fab")
		)
		(pad "1" smd custom
			(at 0 -0.4445 180)
			(size 0.1397 0.1397)
			(layers "F.Cu" "F.Mask" "F.Paste")
			(net "P12V")
			(options
				(clearance outline)
				(anchor circle)
			)
			(primitives
				(gr_poly
					(pts
						(arc
							(start -0.1778 -0.2794)
							(mid -0.249642 -0.249642)
							(end -0.2794 -0.1778)
						)
						(arc
							(start -0.2794 0.1778)
							(mid -0.249642 0.249642)
							(end -0.1778 0.2794)
						)
						(arc
							(start 0.1778 0.2794)
							(mid 0.249642 0.249642)
							(end 0.2794 0.1778)
						)
						(arc
							(start 0.2794 -0.1778)
							(mid 0.249642 -0.249642)
							(end 0.1778 -0.2794)
						)
					)
					(width 0)
					(fill yes)
				)
			)
		)
		(pad "2" smd custom
			(at 0 0.4445 180)
			(size 0.1397 0.1397)
			(layers "F.Cu" "F.Mask" "F.Paste")
			(net "P12V_MOST8_GATE")
			(options
				(clearance outline)
				(anchor circle)
			)
			(primitives
				(gr_poly
					(pts
						(arc
							(start -0.1778 -0.2794)
							(mid -0.249642 -0.249642)
							(end -0.2794 -0.1778)
						)
						(arc
							(start -0.2794 0.1778)
							(mid -0.249642 0.249642)
							(end -0.1778 0.2794)
						)
						(arc
							(start 0.1778 0.2794)
							(mid 0.249642 0.249642)
							(end 0.2794 0.1778)
						)
						(arc
							(start 0.2794 -0.1778)
							(mid 0.249642 -0.249642)
							(end 0.1778 -0.2794)
						)
					)
					(width 0)
					(fill yes)
				)
			)
		)
	)
	(footprint ""
		(layer "F.Cu")
		(at 226.187 -439.166 180)
		(property "Reference" "PR97"
			(at 0 0 180)
			(layer "F.SilkS")
			(hide yes)
			(effects
				(font
					(size 1.27 1.27)
				)
			)
		)
		(property "Value" "10KR2F-2-GP"
			(at 0.064008 -3.993896 180)
			(unlocked yes)
			(layer "F.Fab")
			(hide yes)
			(effects
				(font
					(size 1.016 1.016)
					(thickness 0.1524)
				)
			)
		)
		(property "Device Type" "R402H16"
			(at 0.064008 -5.517896 180)
			(unlocked yes)
			(layer "F.Fab")
			(hide yes)
			(effects
				(font
					(size 1.016 1.016)
					(thickness 0.1524)
				)
			)
		)
		(duplicate_pad_numbers_are_jumpers no)
		(fp_line
			(start 0.508 -0.9398)
			(end -0.508 -0.9398)
			(stroke
				(width 0.1524)
				(type default)
			)
			(layer "F.SilkS")
		)
		(fp_line
			(start -0.508 -0.9398)
			(end -0.508 0.9398)
			(stroke
				(width 0.1524)
				(type default)
			)
			(layer "F.SilkS")
		)
		(fp_rect
			(start -0.508 0.9398)
			(end 0.508 -0.9398)
			(stroke
				(width 0)
				(type default)
			)
			(fill no)
			(layer "F.CrtYd")
		)
		(fp_rect
			(start -0.508 0.9398)
			(end 0.508 -0.9398)
			(stroke
				(width 0)
				(type default)
			)
			(fill no)
			(layer "F.Fab")
		)
		(pad "1" smd custom
			(at 0 -0.4445 180)
			(size 0.1397 0.1397)
			(layers "F.Cu" "F.Mask" "F.Paste")
			(net "P3V3_EN_R")
			(options
				(clearance outline)
				(anchor circle)
			)
			(primitives
				(gr_poly
					(pts
						(arc
							(start -0.1778 -0.2794)
							(mid -0.249642 -0.249642)
							(end -0.2794 -0.1778)
						)
						(arc
							(start -0.2794 0.1778)
							(mid -0.249642 0.249642)
							(end -0.1778 0.2794)
						)
						(arc
							(start 0.1778 0.2794)
							(mid 0.249642 0.249642)
							(end 0.2794 0.1778)
						)
						(arc
							(start 0.2794 -0.1778)
							(mid 0.249642 -0.249642)
							(end 0.1778 -0.2794)
						)
					)
					(width 0)
					(fill yes)
				)
			)
		)
		(pad "2" smd custom
			(at 0 0.4445 180)
			(size 0.1397 0.1397)
			(layers "F.Cu" "F.Mask" "F.Paste")
			(net "AGND_P3V3")
			(options
				(clearance outline)
				(anchor circle)
			)
			(primitives
				(gr_poly
					(pts
						(arc
							(start -0.1778 -0.2794)
							(mid -0.249642 -0.249642)
							(end -0.2794 -0.1778)
						)
						(arc
							(start -0.2794 0.1778)
							(mid -0.249642 0.249642)
							(end -0.1778 0.2794)
						)
						(arc
							(start 0.1778 0.2794)
							(mid 0.249642 0.249642)
							(end 0.2794 0.1778)
						)
						(arc
							(start 0.2794 -0.1778)
							(mid 0.249642 -0.249642)
							(end 0.1778 -0.2794)
						)
					)
					(width 0)
					(fill yes)
				)
			)
		)
	)
	(footprint ""
		(layer "F.Cu")
		(at 82.931 -437.134 90)
		(property "Reference" "SR945"
			(at 0 0 90)
			(layer "F.SilkS")
			(hide yes)
			(effects
				(font
					(size 1.27 1.27)
				)
			)
		)
		(property "Value" "4K7R2F-GP"
			(at 0.064008 -3.993896 90)
			(unlocked yes)
			(layer "F.Fab")
			(hide yes)
			(effects
				(font
					(size 1.016 1.016)
					(thickness 0.1524)
				)
			)
		)
		(property "Device Type" "R402H16"
			(at 0.064008 -5.517896 90)
			(unlocked yes)
			(layer "F.Fab")
			(hide yes)
			(effects
				(font
					(size 1.016 1.016)
					(thickness 0.1524)
				)
			)
		)
		(duplicate_pad_numbers_are_jumpers no)
		(fp_line
			(start 0.508 -0.9398)
			(end -0.508 -0.9398)
			(stroke
				(width 0.1524)
				(type default)
			)
			(layer "F.SilkS")
		)
		(fp_line
			(start -0.508 -0.9398)
			(end -0.508 0.9398)
			(stroke
				(width 0.1524)
				(type default)
			)
			(layer "F.SilkS")
		)
		(fp_rect
			(start -0.508 0.9398)
			(end 0.508 -0.9398)
			(stroke
				(width 0)
				(type default)
			)
			(fill no)
			(layer "F.CrtYd")
		)
		(fp_rect
			(start -0.508 0.9398)
			(end 0.508 -0.9398)
			(stroke
				(width 0)
				(type default)
			)
			(fill no)
			(layer "F.Fab")
		)
		(pad "1" smd custom
			(at 0 -0.4445 90)
			(size 0.1397 0.1397)
			(layers "F.Cu" "F.Mask" "F.Paste")
			(net "VDD_DIFF_1")
			(options
				(clearance outline)
				(anchor circle)
			)
			(primitives
				(gr_poly
					(pts
						(arc
							(start -0.1778 -0.2794)
							(mid -0.249642 -0.249642)
							(end -0.2794 -0.1778)
						)
						(arc
							(start -0.2794 0.1778)
							(mid -0.249642 0.249642)
							(end -0.1778 0.2794)
						)
						(arc
							(start 0.1778 0.2794)
							(mid 0.249642 0.249642)
							(end 0.2794 0.1778)
						)
						(arc
							(start 0.2794 -0.1778)
							(mid 0.249642 -0.249642)
							(end 0.1778 -0.2794)
						)
					)
					(width 0)
					(fill yes)
				)
			)
		)
		(pad "2" smd custom
			(at 0 0.4445 90)
			(size 0.1397 0.1397)
			(layers "F.Cu" "F.Mask" "F.Paste")
			(net "CLK_BUF_EU1_100M_133M#")
			(options
				(clearance outline)
				(anchor circle)
			)
			(primitives
				(gr_poly
					(pts
						(arc
							(start -0.1778 -0.2794)
							(mid -0.249642 -0.249642)
							(end -0.2794 -0.1778)
						)
						(arc
							(start -0.2794 0.1778)
							(mid -0.249642 0.249642)
							(end -0.1778 0.2794)
						)
						(arc
							(start 0.1778 0.2794)
							(mid 0.249642 0.249642)
							(end 0.2794 0.1778)
						)
						(arc
							(start 0.2794 -0.1778)
							(mid 0.249642 -0.249642)
							(end 0.1778 -0.2794)
						)
					)
					(width 0)
					(fill yes)
				)
			)
		)
	)
)
